(kicad_pcb
	(version 20260206)
	(generator "pcbnew")
	(generator_version "10.0")
	(general
		(thickness 1.6)
		(legacy_teardrops no)
	)
	(paper "A4")
	(title_block
		(title "dpb — 14545-sa.0730WZS0815.brd")
		(comment 1 "Honey Badger (Wiwynn) / footprints 18-25 of 1066")
	)
	(layers
		(0 "F.Cu" signal "TOP")
		(4 "In1.Cu" signal "L2GND")
		(6 "In2.Cu" signal "L3")
		(8 "In3.Cu" signal "L4VCC")
		(10 "In4.Cu" signal "L5VCC")
		(12 "In5.Cu" signal "L6")
		(14 "In6.Cu" signal "L7GND")
		(2 "B.Cu" signal "BOTTOM")
		(9 "F.Adhes" user "F.Adhesive")
		(11 "B.Adhes" user "B.Adhesive")
		(13 "F.Paste" user "Package Geometry/Pastemask Top")
		(15 "B.Paste" user "Package Geometry/Pastemask Bottom")
		(5 "F.SilkS" user "Ref Des/Silkscreen Top")
		(7 "B.SilkS" user "Ref Des/Silkscreen Bottom")
		(1 "F.Mask" user "Board Geometry/Soldermask Top")
		(3 "B.Mask" user "Board Geometry/Soldermask Bottom")
		(17 "Dwgs.User" user "User.Drawings")
		(19 "Cmts.User" user "User.Comments")
		(21 "Eco1.User" user "User.Eco1")
		(23 "Eco2.User" user "User.Eco2")
		(25 "Edge.Cuts" user "Board Geometry/Outline")
		(27 "Margin" user)
		(31 "F.CrtYd" user "Package Geometry/Place Bound Top")
		(29 "B.CrtYd" user "Package Geometry/Place Bound Bottom")
		(35 "F.Fab" user "Ref Des/Assembly Top")
		(33 "B.Fab" user "Ref Des/Assembly Bottom")
	)
	(footprint ""
		(layer "F.Cu")
		(at 218.265756 -481.739702)
		(property "Reference" "C108"
			(at 0 0 0)
			(layer "F.SilkS")
			(hide yes)
			(effects
				(font
					(size 1.27 1.27)
				)
			)
		)
		(property "Value" "SCD01U50V2KX-1GP"
			(at 1.1811 -2.7051 0)
			(unlocked yes)
			(layer "F.Fab")
			(hide yes)
			(effects
				(font
					(size 1.016 1.016)
					(thickness 0.1524)
				)
			)
		)
		(property "Device Type" "C402H22"
			(at 1.1811 -4.2291 0)
			(unlocked yes)
			(layer "F.Fab")
			(hide yes)
			(effects
				(font
					(size 1.016 1.016)
					(thickness 0.1524)
				)
			)
		)
		(duplicate_pad_numbers_are_jumpers no)
		(fp_rect
			(start -0.4318 0.9525)
			(end 0.4318 -0.9525)
			(stroke
				(width 0)
				(type default)
			)
			(fill no)
			(layer "F.CrtYd")
		)
		(fp_rect
			(start -0.4318 0.9525)
			(end 0.4318 -0.9525)
			(stroke
				(width 0)
				(type default)
			)
			(fill no)
			(layer "F.Fab")
		)
		(pad "1" smd custom
			(at 0 -0.4445)
			(size 0.1524 0.1524)
			(layers "F.Cu" "F.Mask" "F.Paste")
			(net "HDD_PRSNT_NET0")
			(options
				(clearance outline)
				(anchor circle)
			)
			(primitives
				(gr_poly
					(pts
						(arc
							(start 0.3048 -0.2032)
							(mid 0.275042 -0.275042)
							(end 0.2032 -0.3048)
						)
						(arc
							(start -0.2032 -0.3048)
							(mid -0.275042 -0.275042)
							(end -0.3048 -0.2032)
						)
						(arc
							(start -0.3048 0.2032)
							(mid -0.275042 0.275042)
							(end -0.2032 0.3048)
						)
						(arc
							(start 0.2032 0.3048)
							(mid 0.275042 0.275042)
							(end 0.3048 0.2032)
						)
					)
					(width 0)
					(fill yes)
				)
			)
		)
		(pad "2" smd custom
			(at 0 0.4445)
			(size 0.1524 0.1524)
			(layers "F.Cu" "F.Mask" "F.Paste")
			(net "GND")
			(options
				(clearance outline)
				(anchor circle)
			)
			(primitives
				(gr_poly
					(pts
						(arc
							(start 0.3048 -0.2032)
							(mid 0.275042 -0.275042)
							(end 0.2032 -0.3048)
						)
						(arc
							(start -0.2032 -0.3048)
							(mid -0.275042 -0.275042)
							(end -0.3048 -0.2032)
						)
						(arc
							(start -0.3048 0.2032)
							(mid -0.275042 0.275042)
							(end -0.2032 0.3048)
						)
						(arc
							(start 0.2032 0.3048)
							(mid 0.275042 0.275042)
							(end 0.3048 0.2032)
						)
					)
					(width 0)
					(fill yes)
				)
			)
		)
	)
	(footprint ""
		(layer "F.Cu")
		(at 14.922246 -165.731698 90)
		(property "Reference" "R284"
			(at 0 0 90)
			(layer "F.SilkS")
			(hide yes)
			(effects
				(font
					(size 1.27 1.27)
				)
			)
		)
		(property "Value" "0R2J-2-GP"
			(at 0.064008 -3.993896 90)
			(unlocked yes)
			(layer "F.Fab")
			(hide yes)
			(effects
				(font
					(size 1.016 1.016)
					(thickness 0.1524)
				)
			)
		)
		(property "Device Type" "R402H16"
			(at 0.064008 -5.517896 90)
			(unlocked yes)
			(layer "F.Fab")
			(hide yes)
			(effects
				(font
					(size 1.016 1.016)
					(thickness 0.1524)
				)
			)
		)
		(duplicate_pad_numbers_are_jumpers no)
		(fp_line
			(start 0.508 -0.9398)
			(end -0.508 -0.9398)
			(stroke
				(width 0.1524)
				(type default)
			)
			(layer "F.SilkS")
		)
		(fp_line
			(start -0.508 -0.9398)
			(end -0.508 0.9398)
			(stroke
				(width 0.1524)
				(type default)
			)
			(layer "F.SilkS")
		)
		(fp_rect
			(start -0.508 0.9398)
			(end 0.508 -0.9398)
			(stroke
				(width 0)
				(type default)
			)
			(fill no)
			(layer "F.CrtYd")
		)
		(fp_rect
			(start -0.508 0.9398)
			(end 0.508 -0.9398)
			(stroke
				(width 0)
				(type default)
			)
			(fill no)
			(layer "F.Fab")
		)
		(pad "1" smd custom
			(at 0 -0.4445 90)
			(size 0.1397 0.1397)
			(layers "F.Cu" "F.Mask" "F.Paste")
			(net "DRV_ACT_NET13")
			(options
				(clearance outline)
				(anchor circle)
			)
			(primitives
				(gr_poly
					(pts
						(arc
							(start -0.1778 -0.2794)
							(mid -0.249642 -0.249642)
							(end -0.2794 -0.1778)
						)
						(arc
							(start -0.2794 0.1778)
							(mid -0.249642 0.249642)
							(end -0.1778 0.2794)
						)
						(arc
							(start 0.1778 0.2794)
							(mid 0.249642 0.249642)
							(end 0.2794 0.1778)
						)
						(arc
							(start 0.2794 -0.1778)
							(mid 0.249642 -0.249642)
							(end 0.1778 -0.2794)
						)
					)
					(width 0)
					(fill yes)
				)
			)
		)
		(pad "2" smd custom
			(at 0 0.4445 90)
			(size 0.1397 0.1397)
			(layers "F.Cu" "F.Mask" "F.Paste")
			(net "DRIVE_ACT_13")
			(options
				(clearance outline)
				(anchor circle)
			)
			(primitives
				(gr_poly
					(pts
						(arc
							(start -0.1778 -0.2794)
							(mid -0.249642 -0.249642)
							(end -0.2794 -0.1778)
						)
						(arc
							(start -0.2794 0.1778)
							(mid -0.249642 0.249642)
							(end -0.1778 0.2794)
						)
						(arc
							(start 0.1778 0.2794)
							(mid 0.249642 0.249642)
							(end 0.2794 0.1778)
						)
						(arc
							(start 0.2794 -0.1778)
							(mid 0.249642 -0.249642)
							(end 0.1778 -0.2794)
						)
					)
					(width 0)
					(fill yes)
				)
			)
		)
	)
	(footprint ""
		(layer "F.Cu")
		(at 33.1216 -106.4514)
		(property "Reference" "C315"
			(at 0 0 0)
			(layer "F.SilkS")
			(hide yes)
			(effects
				(font
					(size 1.27 1.27)
				)
			)
		)
		(property "Value" "SCD1U10V2KX-5GP"
			(at 1.1811 -2.7051 0)
			(unlocked yes)
			(layer "F.Fab")
			(hide yes)
			(effects
				(font
					(size 1.016 1.016)
					(thickness 0.1524)
				)
			)
		)
		(property "Device Type" "C402H22"
			(at 1.1811 -4.2291 0)
			(unlocked yes)
			(layer "F.Fab")
			(hide yes)
			(effects
				(font
					(size 1.016 1.016)
					(thickness 0.1524)
				)
			)
		)
		(duplicate_pad_numbers_are_jumpers no)
		(fp_rect
			(start -0.4318 0.9525)
			(end 0.4318 -0.9525)
			(stroke
				(width 0)
				(type default)
			)
			(fill no)
			(layer "F.CrtYd")
		)
		(fp_rect
			(start -0.4318 0.9525)
			(end 0.4318 -0.9525)
			(stroke
				(width 0)
				(type default)
			)
			(fill no)
			(layer "F.Fab")
		)
		(pad "1" smd custom
			(at 0 -0.4445)
			(size 0.1524 0.1524)
			(layers "F.Cu" "F.Mask" "F.Paste")
			(net "P3V3")
			(options
				(clearance outline)
				(anchor circle)
			)
			(primitives
				(gr_poly
					(pts
						(arc
							(start 0.3048 -0.2032)
							(mid 0.275042 -0.275042)
							(end 0.2032 -0.3048)
						)
						(arc
							(start -0.2032 -0.3048)
							(mid -0.275042 -0.275042)
							(end -0.3048 -0.2032)
						)
						(arc
							(start -0.3048 0.2032)
							(mid -0.275042 0.275042)
							(end -0.2032 0.3048)
						)
						(arc
							(start 0.2032 0.3048)
							(mid 0.275042 0.275042)
							(end 0.3048 0.2032)
						)
					)
					(width 0)
					(fill yes)
				)
			)
		)
		(pad "2" smd custom
			(at 0 0.4445)
			(size 0.1524 0.1524)
			(layers "F.Cu" "F.Mask" "F.Paste")
			(net "GND")
			(options
				(clearance outline)
				(anchor circle)
			)
			(primitives
				(gr_poly
					(pts
						(arc
							(start 0.3048 -0.2032)
							(mid 0.275042 -0.275042)
							(end 0.2032 -0.3048)
						)
						(arc
							(start -0.2032 -0.3048)
							(mid -0.275042 -0.275042)
							(end -0.3048 -0.2032)
						)
						(arc
							(start -0.3048 0.2032)
							(mid -0.275042 0.275042)
							(end -0.2032 0.3048)
						)
						(arc
							(start 0.2032 0.3048)
							(mid 0.275042 0.275042)
							(end 0.3048 0.2032)
						)
					)
					(width 0)
					(fill yes)
				)
			)
		)
	)
	(footprint ""
		(layer "F.Cu")
		(at 193.978784 -184.755028 -90)
		(property "Reference" "U12"
			(at 0 0 270)
			(layer "F.SilkS")
			(hide yes)
			(effects
				(font
					(size 1.27 1.27)
				)
			)
		)
		(property "Value" "74LVC1G08GW-1-GP"
			(at -2.3368 -8.6868 270)
			(unlocked yes)
			(layer "F.Fab")
			(hide yes)
			(effects
				(font
					(size 1.016 1.016)
					(thickness 0.1524)
				)
			)
		)
		(property "Device Type" "SC70-5H44"
			(at -2.3114 -10.414 270)
			(unlocked yes)
			(layer "F.Fab")
			(hide yes)
			(effects
				(font
					(size 1.016 1.016)
					(thickness 0.1524)
				)
			)
		)
		(duplicate_pad_numbers_are_jumpers no)
		(fp_line
			(start -1.27 1.7018)
			(end -1.27 -1.7018)
			(stroke
				(width 0.1524)
				(type default)
			)
			(layer "F.SilkS")
		)
		(fp_line
			(start 1.27 1.7018)
			(end -1.27 1.7018)
			(stroke
				(width 0.1524)
				(type default)
			)
			(layer "F.SilkS")
		)
		(fp_line
			(start -1.27 -1.7018)
			(end 1.27 -1.7018)
			(stroke
				(width 0.1524)
				(type default)
			)
			(layer "F.SilkS")
		)
		(fp_line
			(start 1.27 -1.7018)
			(end 1.27 1.7018)
			(stroke
				(width 0.1524)
				(type default)
			)
			(layer "F.SilkS")
		)
		(fp_line
			(start 0.6604 -1.8034)
			(end 1.3843 -1.8034)
			(stroke
				(width 0.3302)
				(type default)
			)
			(layer "F.SilkS")
		)
		(fp_line
			(start 1.3843 -1.8034)
			(end 1.3843 -1.1176)
			(stroke
				(width 0.3302)
				(type default)
			)
			(layer "F.SilkS")
		)
		(fp_rect
			(start -1.524 1.9558)
			(end 1.524 -1.9558)
			(stroke
				(width 0)
				(type default)
			)
			(fill no)
			(layer "F.CrtYd")
		)
		(fp_poly
			(pts
				(xy -1.524 -1.9558) (xy 1.524 -1.9558) (xy 1.524 1.9558) (xy -1.524 1.9558)
			)
			(stroke
				(width 0)
				(type default)
			)
			(fill no)
			(layer "F.Fab")
		)
		(pad "1" smd rect
			(at 0.65024 -0.8255 270)
			(size 0.4064 1.2192)
			(layers "F.Cu" "F.Mask" "F.Paste")
			(net "SAS_EXP_B_PWR3")
		)
		(pad "2" smd rect
			(at 0 -0.8255 270)
			(size 0.4064 1.2192)
			(layers "F.Cu" "F.Mask" "F.Paste")
			(net "SAS_EXP_A_PWR3")
		)
		(pad "3" smd rect
			(at -0.65024 -0.8255 270)
			(size 0.4064 1.2192)
			(layers "F.Cu" "F.Mask" "F.Paste")
			(net "GND")
		)
		(pad "4" smd rect
			(at -0.65024 0.8255 270)
			(size 0.4064 1.2192)
			(layers "F.Cu" "F.Mask" "F.Paste")
			(net "DRIVE_PWR3")
		)
		(pad "5" smd rect
			(at 0.65024 0.8255 270)
			(size 0.4064 1.2192)
			(layers "F.Cu" "F.Mask" "F.Paste")
			(net "P3V3")
		)
	)
	(footprint ""
		(layer "F.Cu")
		(at 8.889746 -399.4277)
		(property "Reference" "TP15"
			(at 0 0 0)
			(layer "F.SilkS")
			(hide yes)
			(effects
				(font
					(size 1.27 1.27)
				)
			)
		)
		(property "Value" "TPAD32-GP"
			(at 0 -3.166364 0)
			(unlocked yes)
			(layer "F.Fab")
			(hide yes)
			(effects
				(font
					(size 1.016 1.016)
					(thickness 0.1524)
				)
			)
		)
		(property "Device Type" "TPAD32"
			(at 0 -4.690618 0)
			(unlocked yes)
			(layer "F.Fab")
			(hide yes)
			(effects
				(font
					(size 1.016 1.016)
					(thickness 0.1524)
				)
			)
		)
		(duplicate_pad_numbers_are_jumpers no)
		(fp_poly
			(pts
				(arc
					(start 0.4064 0)
					(mid -0.4064 0)
					(end 0.4064 0)
				)
			)
			(stroke
				(width 0)
				(type default)
			)
			(fill no)
			(layer "F.CrtYd")
		)
		(fp_poly
			(pts
				(arc
					(start 0.7112 0)
					(mid -0.7112 0)
					(end 0.7112 0)
				)
			)
			(stroke
				(width 0)
				(type default)
			)
			(fill no)
			(layer "F.Fab")
		)
		(pad "1" smd circle
			(at 0 0)
			(size 0.8128 0.8128)
			(layers "F.Cu" "F.Mask" "F.Paste")
			(net "SAS2X28_A_HDD15_FLT")
		)
	)
	(footprint ""
		(layer "F.Cu")
		(at 215.348058 -379.043184 90)
		(property "Reference" "R123"
			(at 0 0 90)
			(layer "F.SilkS")
			(hide yes)
			(effects
				(font
					(size 1.27 1.27)
				)
			)
		)
		(property "Value" "4K7R2J-2-GP"
			(at 0.064008 -3.993896 90)
			(unlocked yes)
			(layer "F.Fab")
			(hide yes)
			(effects
				(font
					(size 1.016 1.016)
					(thickness 0.1524)
				)
			)
		)
		(property "Device Type" "R402H16"
			(at 0.064008 -5.517896 90)
			(unlocked yes)
			(layer "F.Fab")
			(hide yes)
			(effects
				(font
					(size 1.016 1.016)
					(thickness 0.1524)
				)
			)
		)
		(duplicate_pad_numbers_are_jumpers no)
		(fp_line
			(start 0.508 -0.9398)
			(end -0.508 -0.9398)
			(stroke
				(width 0.1524)
				(type default)
			)
			(layer "F.SilkS")
		)
		(fp_line
			(start -0.508 -0.9398)
			(end -0.508 0.9398)
			(stroke
				(width 0.1524)
				(type default)
			)
			(layer "F.SilkS")
		)
		(fp_rect
			(start -0.508 0.9398)
			(end 0.508 -0.9398)
			(stroke
				(width 0)
				(type default)
			)
			(fill no)
			(layer "F.CrtYd")
		)
		(fp_rect
			(start -0.508 0.9398)
			(end 0.508 -0.9398)
			(stroke
				(width 0)
				(type default)
			)
			(fill no)
			(layer "F.Fab")
		)
		(pad "1" smd custom
			(at 0 -0.4445 90)
			(size 0.1397 0.1397)
			(layers "F.Cu" "F.Mask" "F.Paste")
			(net "P3V3")
			(options
				(clearance outline)
				(anchor circle)
			)
			(primitives
				(gr_poly
					(pts
						(arc
							(start -0.1778 -0.2794)
							(mid -0.249642 -0.249642)
							(end -0.2794 -0.1778)
						)
						(arc
							(start -0.2794 0.1778)
							(mid -0.249642 0.249642)
							(end -0.1778 0.2794)
						)
						(arc
							(start 0.1778 0.2794)
							(mid 0.249642 0.249642)
							(end 0.2794 0.1778)
						)
						(arc
							(start 0.2794 -0.1778)
							(mid 0.249642 -0.249642)
							(end 0.1778 -0.2794)
						)
					)
					(width 0)
					(fill yes)
				)
			)
		)
		(pad "2" smd custom
			(at 0 0.4445 90)
			(size 0.1397 0.1397)
			(layers "F.Cu" "F.Mask" "F.Paste")
			(net "HDD_PRSNT_NET1")
			(options
				(clearance outline)
				(anchor circle)
			)
			(primitives
				(gr_poly
					(pts
						(arc
							(start -0.1778 -0.2794)
							(mid -0.249642 -0.249642)
							(end -0.2794 -0.1778)
						)
						(arc
							(start -0.2794 0.1778)
							(mid -0.249642 0.249642)
							(end -0.1778 0.2794)
						)
						(arc
							(start 0.1778 0.2794)
							(mid 0.249642 0.249642)
							(end 0.2794 0.1778)
						)
						(arc
							(start 0.2794 -0.1778)
							(mid 0.249642 -0.249642)
							(end 0.1778 -0.2794)
						)
					)
					(width 0)
					(fill yes)
				)
			)
		)
	)
	(footprint ""
		(layer "F.Cu")
		(at 38.099746 -120.5357 90)
		(property "Reference" "R292"
			(at 0 0 90)
			(layer "F.SilkS")
			(hide yes)
			(effects
				(font
					(size 1.27 1.27)
				)
			)
		)
		(property "Value" "2R2010J-1-GP"
			(at 0.254 -8.0772 90)
			(unlocked yes)
			(layer "F.Fab")
			(hide yes)
			(effects
				(font
					(size 1.016 1.016)
					(thickness 0.1524)
				)
			)
		)
		(property "Device Type" "R2010H28"
			(at 0.254 -9.6774 90)
			(unlocked yes)
			(layer "F.Fab")
			(hide yes)
			(effects
				(font
					(size 1.016 1.016)
					(thickness 0.1524)
				)
			)
		)
		(duplicate_pad_numbers_are_jumpers no)
		(fp_line
			(start 1.651 -3.302)
			(end -1.651 -3.302)
			(stroke
				(width 0.1524)
				(type default)
			)
			(layer "F.SilkS")
		)
		(fp_line
			(start -1.651 -3.302)
			(end -1.651 3.302)
			(stroke
				(width 0.1524)
				(type default)
			)
			(layer "F.SilkS")
		)
		(fp_line
			(start 1.651 3.302)
			(end 1.651 -3.302)
			(stroke
				(width 0.1524)
				(type default)
			)
			(layer "F.SilkS")
		)
		(fp_line
			(start -1.651 3.302)
			(end 1.651 3.302)
			(stroke
				(width 0.1524)
				(type default)
			)
			(layer "F.SilkS")
		)
		(fp_rect
			(start -1.7272 -3.3782)
			(end 1.7272 3.3782)
			(stroke
				(width 0)
				(type default)
			)
			(fill no)
			(layer "F.CrtYd")
		)
		(fp_poly
			(pts
				(xy 1.7272 3.3782) (xy 1.7272 -3.3782) (xy -1.7272 -3.3782) (xy -1.7272 3.3782)
			)
			(stroke
				(width 0)
				(type default)
			)
			(fill no)
			(layer "F.Fab")
		)
		(pad "1" smd rect
			(at 0 -2.3495 90)
			(size 2.794 1.143)
			(layers "F.Cu" "F.Mask" "F.Paste")
			(net "12V_PRE_13")
		)
		(pad "2" smd rect
			(at 0 2.3495 90)
			(size 2.794 1.143)
			(layers "F.Cu" "F.Mask" "F.Paste")
			(net "P12V_HDD13")
		)
	)
	(footprint ""
		(layer "F.Cu")
		(at 25.79243 -236.598206 90)
		(property "Reference" "C296"
			(at 0 0 90)
			(layer "F.SilkS")
			(hide yes)
			(effects
				(font
					(size 1.27 1.27)
				)
			)
		)
		(property "Value" "SCD01U50V2KX-1GP"
			(at 1.1811 -2.7051 90)
			(unlocked yes)
			(layer "F.Fab")
			(hide yes)
			(effects
				(font
					(size 1.016 1.016)
					(thickness 0.1524)
				)
			)
		)
		(property "Device Type" "C402H22"
			(at 1.1811 -4.2291 90)
			(unlocked yes)
			(layer "F.Fab")
			(hide yes)
			(effects
				(font
					(size 1.016 1.016)
					(thickness 0.1524)
				)
			)
		)
		(duplicate_pad_numbers_are_jumpers no)
		(fp_rect
			(start -0.4318 0.9525)
			(end 0.4318 -0.9525)
			(stroke
				(width 0)
				(type default)
			)
			(fill no)
			(layer "F.CrtYd")
		)
		(fp_rect
			(start -0.4318 0.9525)
			(end 0.4318 -0.9525)
			(stroke
				(width 0)
				(type default)
			)
			(fill no)
			(layer "F.Fab")
		)
		(pad "1" smd custom
			(at 0 -0.4445 90)
			(size 0.1524 0.1524)
			(layers "F.Cu" "F.Mask" "F.Paste")
			(net "SAS2X28_DRIVE_RX_N_B12")
			(options
				(clearance outline)
				(anchor circle)
			)
			(primitives
				(gr_poly
					(pts
						(arc
							(start 0.3048 -0.2032)
							(mid 0.275042 -0.275042)
							(end 0.2032 -0.3048)
						)
						(arc
							(start -0.2032 -0.3048)
							(mid -0.275042 -0.275042)
							(end -0.3048 -0.2032)
						)
						(arc
							(start -0.3048 0.2032)
							(mid -0.275042 0.275042)
							(end -0.2032 0.3048)
						)
						(arc
							(start 0.2032 0.3048)
							(mid 0.275042 0.275042)
							(end 0.3048 0.2032)
						)
					)
					(width 0)
					(fill yes)
				)
			)
		)
		(pad "2" smd custom
			(at 0 0.4445 90)
			(size 0.1524 0.1524)
			(layers "F.Cu" "F.Mask" "F.Paste")
			(net "SAS2X28_B_HDD12_RX_-")
			(options
				(clearance outline)
				(anchor circle)
			)
			(primitives
				(gr_poly
					(pts
						(arc
							(start 0.3048 -0.2032)
							(mid 0.275042 -0.275042)
							(end 0.2032 -0.3048)
						)
						(arc
							(start -0.2032 -0.3048)
							(mid -0.275042 -0.275042)
							(end -0.3048 -0.2032)
						)
						(arc
							(start -0.3048 0.2032)
							(mid -0.275042 0.275042)
							(end -0.2032 0.3048)
						)
						(arc
							(start 0.2032 0.3048)
							(mid 0.275042 0.275042)
							(end 0.3048 0.2032)
						)
					)
					(width 0)
					(fill yes)
				)
			)
		)
	)
)
